FILE_TYPE = MACRO_DRAWING;
SET COLOR_WIRE YELLOW;
SET COLOR_PROP ORANGE;
SET COLOR_DOT WHITE;
SET COLOR_ARC YELLOW;
SET COLOR_BODY GREEN;
SET COLOR_NOTE PURPLE;
SET PROP_DISPLAY VALUE;
SET PAGE_NUMBER P6;
FORCEADD QUANTA_TITLE_BLOCK_C..1
(6150 -1300);
FORCEPROP 1 LAST CUSTOM_TXT_CDS <NAME_2>
J 0
(2975 -1250);
FORCEPROP 1 LAST CUSTOM_TXT_CDS <NAME_1>
J 0
(2975 -1125);
FORCEPROP 1 LAST CUSTOM_TXT_CDS <Q_NUMBER>
J 0
(4747 -1197);
DISPLAY 1.212766 (4747 -1197);
FORCEPROP 1 LAST CUSTOM_TXT_CDS <Q_PROJ>
J 0
(3768 -1198);
DISPLAY 1.212766 (3768 -1198);
FORCEPROP 1 LAST CUSTOM_TXT_CDS <Q_REV>
J 0
(5966 -1197);
DISPLAY 1.212766 (5966 -1197);
FORCEPROP 1 LAST CUSTOM_TXT_CDS <CON_LAST_MODIFIED>
J 0
(4265 -1285);
DISPLAY 0.978723 (4265 -1285);
FORCEPROP 1 LAST CUSTOM_TXT_CDS <CON_PAGE_NUM> OF <CON_TOTAL_PAGES>
J 0
(5704 -1282);
DISPLAY 0.978723 (5704 -1282);
FORCEPROP 1 LAST Q_TITLE BLOCK DIAGRAM - SPI
J 0
(-3216 -1274);
DISPLAY 2.446809 (-3216 -1274);
PAINT GREEN (-3216 -1274);
FORCEPROP 1 LAST Q_DEPT 
J 1
(2387 -1251);
DISPLAY 1.957447 (2387 -1251);
PAINT GREEN (2387 -1251);
FORCEPROP 2 LAST PAGE_BORDER TRUE
J 0
(-1740 3950);
DISPLAY 0.638298 (-1740 3950);
PAINT PINK (-1740 3950);
DISPLAY INVISIBLE (-1740 3950);
FORCEPROP 1 LAST COMMENT_BODY TRUE
J 0
(6162 -1313);
DISPLAY 0.978723 (6162 -1313);
PAINT GREEN (6162 -1313);
DISPLAY INVISIBLE (6162 -1313);
FORCEPROP 1 LAST CDS_LMAN_SYM_OUTLINE -9475,6775,100,-125
J 0
(6150 -1300);
DISPLAY 0.468085 (6150 -1300);
PAINT GREEN (6150 -1300);
DISPLAY INVISIBLE (6150 -1300);
FORCEPROP 2 LAST CDS_LIB pure_quanta
J 0
(6150 -1300);
PAINT MONO (6150 -1300);
DISPLAY INVISIBLE (6150 -1300);
FORCEPROP 2 LAST CDS_XR_PAGE_TITLE CR-6 : @S9S_MB_2U_LIB.S9S_MB_2U(SCH_1):PAGE6
J 0
(-1740 3950);
DISPLAY 0.638298 (-1740 3950);
PAINT PINK (-1740 3950);
DISPLAY INVISIBLE (-1740 3950);
FORCEPROP 2 LAST CUSTOM_TXT_CDS <XR_PAGE_TITLE>
J 0
(-1740 3950);
DISPLAY 0.638298 (-1740 3950);
PAINT PINK (-1740 3950);
DISPLAY INVISIBLE (-1740 3950);
FORCEPROP 0 LAST CDS_CON_LAST_MODIFIED Thu Aug 24 16:11:58 2023
J 0
(4265 -1285);
PAINT MONO (4265 -1285);
DISPLAY INVISIBLE (4265 -1285);
FORCENOTE
$CDS_IMAGE|F0T_diagram_MB_20211130_rev1-SPI.jpg|7929|6240
(1500 2200) 0;
DISPLAY LEFT (1500 2200);
QUIT
